(kicad_pcb
	(version 20221018)
	(generator pcbnew)
	(general
    (thickness 1.586)
  )
	(paper "A4")
	(title_block
    (date "2024-03-26")
    (rev "1.1.3")
		(comment 9 "footprints 139-146 of 146")
	)
	(layers
    (0 "F.Cu" signal)
    (1 "In1.Cu" power)
    (2 "In2.Cu" power)
    (31 "B.Cu" signal)
    (32 "B.Adhes" user "B.Adhesive")
    (33 "F.Adhes" user "F.Adhesive")
    (34 "B.Paste" user)
    (35 "F.Paste" user)
    (36 "B.SilkS" user "B.Silkscreen")
    (37 "F.SilkS" user "F.Silkscreen")
    (38 "B.Mask" user)
    (39 "F.Mask" user)
    (40 "Dwgs.User" user "User.Drawings")
    (41 "Cmts.User" user "User.Comments")
    (42 "Eco1.User" user "User.Eco1")
    (43 "Eco2.User" user "User.Eco2")
    (44 "Edge.Cuts" user)
    (45 "Margin" user)
    (46 "B.CrtYd" user "B.Courtyard")
    (47 "F.CrtYd" user "F.Courtyard")
    (48 "B.Fab" user)
    (49 "F.Fab" user)
  )
	(footprint "scalenode-cm4-baseboard-footprints:DO-214AC" (layer "B.Cu")
    (at 90.5 92.006 90)
    (property "Author" "Antmicro")
    (property "License" "Apache-2.0")
    (property "MPN" "SMAJ58A-13-F")
    (property "Manufacturer" "Diodes Incorporated")
    (property "Sheetfile" "poe.kicad_sch")
    (property "Sheetname" "PoE")
    (attr smd)
    (fp_text reference "D6" (at 3.481 0.925) (layer "B.SilkS")
        (effects (font (size 0.7 0.7) (thickness 0.15)) (justify left bottom mirror))
    )
    (fp_text value "SMAJ58A-13-F" (at 3.881 -2.75 270) (layer "B.Fab")
        (effects (font (size 0.7 0.7) (thickness 0.15)) (justify left bottom mirror))
    )
    (fp_text user "Author: Antmicro" (at -3.301 -5.65 270) (layer "B.Fab") hide
        (effects (font (size 0.7 0.7) (thickness 0.15)) (justify left bottom mirror))
    )
    (fp_text user "License: Apache-2.0" (at -3.301 -6.85 270) (layer "B.Fab") hide
        (effects (font (size 0.7 0.7) (thickness 0.15)) (justify left bottom mirror))
    )
    (fp_text user "${REFERENCE}" (at -3.301 -4.45 270) (layer "B.Fab") hide
        (effects (font (size 0.7 0.7) (thickness 0.15)) (justify left bottom mirror))
    )
    (fp_line (start -3.301 -1.5) (end 0 -1.5)
      (stroke (width 0.15) (type solid)) (layer "B.SilkS"))
    (fp_line (start -3.301 1.5) (end -3.301 -1.5)
      (stroke (width 0.15) (type solid)) (layer "B.SilkS"))
    (fp_line (start 0 1.5) (end -3.301 1.5)
      (stroke (width 0.15) (type solid)) (layer "B.SilkS"))
    (fp_rect (start -3.25 1.55) (end 3.25 -1.55)
      (stroke (width 0.05) (type solid)) (fill none) (layer "B.CrtYd"))
    (fp_line (start -2.15 -1.3) (end 2.148 -1.3)
      (stroke (width 0.15) (type solid)) (layer "B.Fab"))
    (fp_line (start -2.15 1.301) (end -2.15 -1.3)
      (stroke (width 0.15) (type solid)) (layer "B.Fab"))
    (fp_line (start -2.15 1.301) (end 2.148 1.301)
      (stroke (width 0.15) (type solid)) (layer "B.Fab"))
    (fp_line (start -1.442 -1.3) (end -1.365 -1.3)
      (stroke (width 0.15) (type solid)) (layer "B.Fab"))
    (fp_line (start -1.363 1.301) (end -1.442 1.301)
      (stroke (width 0.15) (type solid)) (layer "B.Fab"))
    (fp_line (start 2.148 1.301) (end 2.148 -1.3)
      (stroke (width 0.15) (type solid)) (layer "B.Fab"))
    (fp_rect (start -1.363 1.301) (end -1.1 -1.3)
      (stroke (width 0.15) (type solid)) (fill solid) (layer "B.Fab"))
    (pad "A" smd roundrect (at 1.999 0 90) (size 2 2.1) (layers "B.Cu" "B.Paste" "B.Mask") (roundrect_rratio 0.1)
      (net 5 "VSS") (pinfunction "A") (pintype "passive"))
    (pad "K" smd roundrect (at -2 0 90) (size 2 2.1) (layers "B.Cu" "B.Paste" "B.Mask") (roundrect_rratio 0.1)
      (net 6 "/PoE/VDD_POE_IN") (pinfunction "K") (pintype "passive"))
  )
	(footprint "scalenode-cm4-baseboard-footprints:R_0402_1005Metric" (layer "B.Cu")
    (at 102.8 73.506)
    (descr "Resistor SMD 0402")
    (tags "resistor SMD 0402")
    (property "Author" "Antmicro")
    (property "License" "Apache-2.0")
    (property "MPN" "CR0402-FX-75R0GLF")
    (property "Manufacturer" "Bourns")
    (property "Sheetfile" "poe.kicad_sch")
    (property "Sheetname" "PoE")
    (property "Tolerance" "1%")
    (property "Val" "75R")
    (property "ki_description" "75R resistor in 0402 package with 1% tolerance")
    (attr smd)
    (fp_text reference "R25" (at 3.06 0.174 180) (layer "B.SilkS")
        (effects (font (size 0.7 0.7) (thickness 0.15)) (justify left bottom mirror))
    )
    (fp_text value "R_75R_0402" (at 0 -1.4 180) (layer "B.Fab")
        (effects (font (size 0.7 0.7) (thickness 0.15)) (justify left bottom mirror))
    )
    (fp_text user "License: Apache-2.0" (at -0.95 -5.169 180) (layer "B.Fab") hide
        (effects (font (size 0.7 0.7) (thickness 0.15)) (justify left bottom mirror))
    )
    (fp_text user "${REFERENCE}" (at -0.95 -3.168 180) (layer "B.Fab") hide
        (effects (font (size 0.7 0.7) (thickness 0.15)) (justify left bottom mirror))
    )
    (fp_text user "Author: Antmicro" (at -0.95 -4.169 180) (layer "B.Fab") hide
        (effects (font (size 0.7 0.7) (thickness 0.15)) (justify left bottom mirror))
    )
    (fp_rect (start -0.95 0.48) (end 0.95 -0.48)
      (stroke (width 0.05) (type solid)) (fill none) (layer "B.CrtYd"))
    (fp_rect (start -0.5 0.25) (end 0.5 -0.25)
      (stroke (width 0.15) (type solid)) (fill none) (layer "B.Fab"))
    (pad "1" smd roundrect (at -0.485 0) (size 0.59 0.64) (layers "B.Cu" "B.Paste" "B.Mask") (roundrect_rratio 0.25)
      (net 7 "Net-(C27-Pad1)") (pintype "passive"))
    (pad "2" smd roundrect (at 0.485 0) (size 0.59 0.64) (layers "B.Cu" "B.Paste" "B.Mask") (roundrect_rratio 0.25)
      (net 8 "Net-(C31-Pad1)") (pintype "passive"))
  )
	(footprint "scalenode-cm4-baseboard-footprints:C_2220_5650Metric" (layer "B.Cu")
    (at 107.354191 92.524276 -90)
    (descr "Capacitor SMD 2220")
    (tags "capacitor SMD 2220")
    (property "Author" "Antmicro")
    (property "Dielectric" "X7S")
    (property "License" "Apache-2.0")
    (property "MPN" "C5750X7S2A226M280KB")
    (property "Manufacturer" "TDK")
    (property "Sheetfile" "poe.kicad_sch")
    (property "Sheetname" "PoE")
    (property "Val" "22u")
    (property "Voltage" "100V")
    (property "ki_description" " ")
    (attr smd)
    (fp_text reference "C28" (at -4.054276 -1.485809 180) (layer "B.SilkS")
        (effects (font (size 0.7 0.7) (thickness 0.15)) (justify left bottom mirror))
    )
    (fp_text value "C_22u_100V_2220" (at -9.416 -2.833 90) (layer "B.Fab")
        (effects (font (size 0.7 0.7) (thickness 0.15)) (justify left bottom mirror))
    )
    (fp_text user "License: Apache-2.0" (at -3.7 -6.9 90) (layer "B.Fab") hide
        (effects (font (size 0.7 0.7) (thickness 0.15)) (justify left bottom mirror))
    )
    (fp_text user "Author: Antmicro" (at -3.7 -7.9 90) (layer "B.Fab") hide
        (effects (font (size 0.7 0.7) (thickness 0.15)) (justify left bottom mirror))
    )
    (fp_text user "${REFERENCE}" (at -3.7 -5.9 90) (layer "B.Fab") hide
        (effects (font (size 0.7 0.7) (thickness 0.15)) (justify left bottom mirror))
    )
    (fp_line (start -1.415 -2.61) (end 1.415 -2.61)
      (stroke (width 0.15) (type solid)) (layer "B.SilkS"))
    (fp_line (start -1.415 2.61) (end 1.415 2.61)
      (stroke (width 0.15) (type solid)) (layer "B.SilkS"))
    (fp_rect (start -3.7 2.95) (end 3.7 -2.95)
      (stroke (width 0.05) (type solid)) (fill none) (layer "B.CrtYd"))
    (fp_rect (start -2.85 2.5) (end 2.85 -2.5)
      (stroke (width 0.15) (type solid)) (fill none) (layer "B.Fab"))
    (pad "1" smd roundrect (at -2.55 0 270) (size 1.8 5.4) (layers "B.Cu" "B.Paste" "B.Mask") (roundrect_rratio 0.138889)
      (net 4 "GNDD") (pintype "passive"))
    (pad "2" smd roundrect (at 2.55 0 270) (size 1.8 5.4) (layers "B.Cu" "B.Paste" "B.Mask") (roundrect_rratio 0.138889)
      (net 6 "/PoE/VDD_POE_IN") (pintype "passive"))
  )
	(footprint "scalenode-cm4-baseboard-footprints:C_0402_1005Metric" (layer "B.Cu")
    (at 102.785 67.006 180)
    (descr "Capacitor SMD 0402")
    (tags "capacitor SMD 0402")
    (property "Author" "Antmicro")
    (property "Dielectric" "X7R")
    (property "License" "Apache-2.0")
    (property "MPN" "GRM155R71H103KA88D")
    (property "Manufacturer" "Murata")
    (property "Sheetfile" "poe.kicad_sch")
    (property "Sheetname" "PoE")
    (property "Val" "10n")
    (property "Voltage" "50V")
    (property "ki_description" " ")
    (attr smd)
    (fp_text reference "C33" (at -3.115 -0.444) (layer "B.SilkS")
        (effects (font (size 0.7 0.7) (thickness 0.15)) (justify left bottom mirror))
    )
    (fp_text value "C_10n_0402" (at 0 -1.4) (layer "B.Fab")
        (effects (font (size 0.7 0.7) (thickness 0.15)) (justify left bottom mirror))
    )
    (fp_text user "${REFERENCE}" (at -0.932 -3.168) (layer "B.Fab") hide
        (effects (font (size 0.7 0.7) (thickness 0.15)) (justify left bottom mirror))
    )
    (fp_text user "Author: Antmicro" (at -0.932 -4.17) (layer "B.Fab") hide
        (effects (font (size 0.7 0.7) (thickness 0.15)) (justify left bottom mirror))
    )
    (fp_text user "License: Apache-2.0" (at -0.932 -5.17) (layer "B.Fab") hide
        (effects (font (size 0.7 0.7) (thickness 0.15)) (justify left bottom mirror))
    )
    (fp_rect (start -0.94 0.47) (end 0.94 -0.47)
      (stroke (width 0.05) (type solid)) (fill none) (layer "B.CrtYd"))
    (fp_rect (start -0.499 0.249) (end 0.499 -0.249)
      (stroke (width 0.15) (type solid)) (fill none) (layer "B.Fab"))
    (pad "1" smd roundrect (at -0.484 0 180) (size 0.59 0.64) (layers "B.Cu" "B.Paste" "B.Mask") (roundrect_rratio 0.25)
      (net 10 "Net-(C33-Pad1)") (pintype "passive"))
    (pad "2" smd roundrect (at 0.484 0 180) (size 0.59 0.64) (layers "B.Cu" "B.Paste" "B.Mask") (roundrect_rratio 0.25)
      (net 3 "/PoE/PAIR45") (pintype "passive"))
  )
	(footprint "scalenode-cm4-baseboard-footprints:C_0402_1005Metric" (layer "B.Cu")
    (at 102.8 72.206 180)
    (descr "Capacitor SMD 0402")
    (tags "capacitor SMD 0402")
    (property "Author" "Antmicro")
    (property "Dielectric" "X7R")
    (property "License" "Apache-2.0")
    (property "MPN" "GRM155R71H103KA88D")
    (property "Manufacturer" "Murata")
    (property "Sheetfile" "poe.kicad_sch")
    (property "Sheetname" "PoE")
    (property "Val" "10n")
    (property "Voltage" "50V")
    (property "ki_description" " ")
    (attr smd)
    (fp_text reference "C30" (at -3.13 -0.314) (layer "B.SilkS")
        (effects (font (size 0.7 0.7) (thickness 0.15)) (justify left bottom mirror))
    )
    (fp_text value "C_10n_0402" (at 0 -1.4) (layer "B.Fab")
        (effects (font (size 0.7 0.7) (thickness 0.15)) (justify left bottom mirror))
    )
    (fp_text user "License: Apache-2.0" (at -0.932 -5.17) (layer "B.Fab") hide
        (effects (font (size 0.7 0.7) (thickness 0.15)) (justify left bottom mirror))
    )
    (fp_text user "Author: Antmicro" (at -0.932 -4.17) (layer "B.Fab") hide
        (effects (font (size 0.7 0.7) (thickness 0.15)) (justify left bottom mirror))
    )
    (fp_text user "${REFERENCE}" (at -0.932 -3.168) (layer "B.Fab") hide
        (effects (font (size 0.7 0.7) (thickness 0.15)) (justify left bottom mirror))
    )
    (fp_rect (start -0.94 0.47) (end 0.94 -0.47)
      (stroke (width 0.05) (type solid)) (fill none) (layer "B.CrtYd"))
    (fp_rect (start -0.499 0.249) (end 0.499 -0.249)
      (stroke (width 0.15) (type solid)) (fill none) (layer "B.Fab"))
    (pad "1" smd roundrect (at -0.484 0 180) (size 0.59 0.64) (layers "B.Cu" "B.Paste" "B.Mask") (roundrect_rratio 0.25)
      (net 9 "Net-(C30-Pad1)") (pintype "passive"))
    (pad "2" smd roundrect (at 0.484 0 180) (size 0.59 0.64) (layers "B.Cu" "B.Paste" "B.Mask") (roundrect_rratio 0.25)
      (net 2 "/PoE/PAIR36") (pintype "passive"))
  )
	(footprint "scalenode-cm4-baseboard-footprints:R_0402_1005Metric" (layer "B.Cu")
    (at 94.65 90.306 -90)
    (descr "Resistor SMD 0402")
    (tags "resistor SMD 0402")
    (property "Author" "Antmicro")
    (property "License" "Apache-2.0")
    (property "MPN" "CR0402-FX-63R4GLF")
    (property "Manufacturer" "Bourns")
    (property "Sheetfile" "poe.kicad_sch")
    (property "Sheetname" "PoE")
    (property "Tolerance" "1%")
    (property "Val" "63R4")
    (property "ki_description" "63R4 resistor in 0402 package with 1% tolerance")
    (attr smd)
    (fp_text reference "R23" (at -0.881 -0.375 -90) (layer "B.SilkS")
        (effects (font (size 0.7 0.7) (thickness 0.15)) (justify right bottom mirror))
    )
    (fp_text value "R_63R4_0402" (at -1.246 -2.07 90) (layer "B.Fab")
        (effects (font (size 0.7 0.7) (thickness 0.15)) (justify left bottom mirror))
    )
    (fp_text user "${REFERENCE}" (at -0.95 -3.168 90) (layer "B.Fab") hide
        (effects (font (size 0.7 0.7) (thickness 0.15)) (justify left bottom mirror))
    )
    (fp_text user "License: Apache-2.0" (at -0.95 -5.169 90) (layer "B.Fab") hide
        (effects (font (size 0.7 0.7) (thickness 0.15)) (justify left bottom mirror))
    )
    (fp_text user "Author: Antmicro" (at -0.95 -4.169 90) (layer "B.Fab") hide
        (effects (font (size 0.7 0.7) (thickness 0.15)) (justify left bottom mirror))
    )
    (fp_rect (start -0.95 0.48) (end 0.95 -0.48)
      (stroke (width 0.05) (type solid)) (fill none) (layer "B.CrtYd"))
    (fp_rect (start -0.5 0.25) (end 0.5 -0.25)
      (stroke (width 0.15) (type solid)) (fill none) (layer "B.Fab"))
    (pad "1" smd roundrect (at -0.485 0 270) (size 0.59 0.64) (layers "B.Cu" "B.Paste" "B.Mask") (roundrect_rratio 0.25)
      (net 5 "VSS") (pintype "passive"))
    (pad "2" smd roundrect (at 0.485 0 270) (size 0.59 0.64) (layers "B.Cu" "B.Paste" "B.Mask") (roundrect_rratio 0.25)
      (net 255 "Net-(U8-CLS)") (pintype "passive"))
  )
	(footprint "scalenode-cm4-baseboard-footprints:C_0805_2012Metric" (layer "B.Cu")
    (at 93 91.506 -90)
    (descr "Capacitor SMD 0805")
    (tags "capacitor SMD 0805")
    (property "Author" "Antmicro")
    (property "Dielectric" "X7R")
    (property "License" "Apache-2.0")
    (property "MPN" "CL21B104KCFNNNE")
    (property "Manufacturer" "Samsung Electro-Mechanics")
    (property "Sheetfile" "poe.kicad_sch")
    (property "Sheetname" "PoE")
    (property "Val" "100n")
    (property "Voltage" "100V")
    (property "ki_description" " ")
    (attr smd)
    (fp_text reference "C20" (at 0 1.176 90) (layer "B.SilkS")
        (effects (font (size 0.7 0.7) (thickness 0.15)) (justify left bottom mirror))
    )
    (fp_text value "C_100n_100V_0805" (at -9.416 -0.88 90) (layer "B.Fab")
        (effects (font (size 0.7 0.7) (thickness 0.15)) (justify left bottom mirror))
    )
    (fp_text user "Author: Antmicro" (at -1.9 -5.947 90) (layer "B.Fab") hide
        (effects (font (size 0.7 0.7) (thickness 0.15)) (justify left bottom mirror))
    )
    (fp_text user "${REFERENCE}" (at -1.9 -3.947 90) (layer "B.Fab") hide
        (effects (font (size 0.7 0.7) (thickness 0.15)) (justify left bottom mirror))
    )
    (fp_text user "License: Apache-2.0" (at -1.9 -4.947 90) (layer "B.Fab") hide
        (effects (font (size 0.7 0.7) (thickness 0.15)) (justify left bottom mirror))
    )
    (fp_line (start -0.3 -0.8) (end 0.3 -0.8)
      (stroke (width 0.15) (type solid)) (layer "B.SilkS"))
    (fp_line (start -0.3 0.8) (end 0.3 0.8)
      (stroke (width 0.15) (type solid)) (layer "B.SilkS"))
    (fp_rect (start -1.9 0.93) (end 1.9 -0.93)
      (stroke (width 0.05) (type solid)) (fill none) (layer "B.CrtYd"))
    (fp_rect (start -0.95 0.675) (end 0.95 -0.675)
      (stroke (width 0.15) (type solid)) (fill none) (layer "B.Fab"))
    (pad "1" smd rect (at -1.05 0 270) (size 1.2 1.2) (layers "B.Cu" "B.Paste" "B.Mask")
      (net 5 "VSS") (pintype "passive"))
    (pad "2" smd rect (at 1.05 0 270) (size 1.2 1.2) (layers "B.Cu" "B.Paste" "B.Mask")
      (net 6 "/PoE/VDD_POE_IN") (pintype "passive"))
  )
	(footprint "scalenode-cm4-baseboard-footprints:R_0402_1005Metric" (layer "B.Cu")
    (at 94.65 92.756 90)
    (descr "Resistor SMD 0402")
    (tags "resistor SMD 0402")
    (property "Author" "Antmicro")
    (property "License" "Apache-2.0")
    (property "MPN" "CR0402-FX-2492GLF")
    (property "Manufacturer" "Bourns")
    (property "Sheetfile" "poe.kicad_sch")
    (property "Sheetname" "PoE")
    (property "Tolerance" "1%")
    (property "Val" "24k9")
    (property "ki_description" "24k9 resistor in 0402 package with 1% tolerance")
    (attr smd)
    (fp_text reference "R24" (at -1.019 0.375 90) (layer "B.SilkS")
        (effects (font (size 0.7 0.7) (thickness 0.15)) (justify left bottom mirror))
    )
    (fp_text value "R_24k9_0402" (at 5.106 -0.15 270) (layer "B.Fab")
        (effects (font (size 0.7 0.7) (thickness 0.15)) (justify left bottom mirror))
    )
    (fp_text user "License: Apache-2.0" (at -0.95 -5.169 270) (layer "B.Fab") hide
        (effects (font (size 0.7 0.7) (thickness 0.15)) (justify left bottom mirror))
    )
    (fp_text user "Author: Antmicro" (at -0.95 -4.169 270) (layer "B.Fab") hide
        (effects (font (size 0.7 0.7) (thickness 0.15)) (justify left bottom mirror))
    )
    (fp_text user "${REFERENCE}" (at -0.95 -3.168 270) (layer "B.Fab") hide
        (effects (font (size 0.7 0.7) (thickness 0.15)) (justify left bottom mirror))
    )
    (fp_rect (start -0.95 0.48) (end 0.95 -0.48)
      (stroke (width 0.05) (type solid)) (fill none) (layer "B.CrtYd"))
    (fp_rect (start -0.5 0.25) (end 0.5 -0.25)
      (stroke (width 0.15) (type solid)) (fill none) (layer "B.Fab"))
    (pad "1" smd roundrect (at -0.485 0 90) (size 0.59 0.64) (layers "B.Cu" "B.Paste" "B.Mask") (roundrect_rratio 0.25)
      (net 6 "/PoE/VDD_POE_IN") (pintype "passive"))
    (pad "2" smd roundrect (at 0.485 0 90) (size 0.59 0.64) (layers "B.Cu" "B.Paste" "B.Mask") (roundrect_rratio 0.25)
      (net 256 "Net-(U8-DEN)") (pintype "passive"))
  )
)
